(kicad_pcb
	(version 20260206)
	(generator "pcbnew")
	(generator_version "10.0")
	(general
		(thickness 1.6)
		(legacy_teardrops no)
	)
	(paper "A4")
	(title_block
		(title "04192023_DAF0TMB3IC0_F0TG_MB_C_brd_V02_OCP.brd")
		(comment 1 "Grand Teton / footprints 5964-5970 of 8354")
	)
	(layers
		(0 "F.Cu" signal "TOP")
		(4 "In1.Cu" signal "GND")
		(6 "In2.Cu" signal "IN1")
		(8 "In3.Cu" signal "GND1")
		(10 "In4.Cu" signal "IN2")
		(12 "In5.Cu" signal "GND2")
		(14 "In6.Cu" signal "IN3")
		(16 "In7.Cu" signal "GND3")
		(18 "In8.Cu" signal "VCC")
		(20 "In9.Cu" signal "VCC1")
		(22 "In10.Cu" signal "GND4")
		(24 "In11.Cu" signal "IN4")
		(26 "In12.Cu" signal "GND5")
		(28 "In13.Cu" signal "IN5")
		(30 "In14.Cu" signal "GND6")
		(32 "In15.Cu" signal "IN6")
		(34 "In16.Cu" signal "GND7")
		(2 "B.Cu" signal "BOTTOM")
		(9 "F.Adhes" user "F.Adhesive")
		(11 "B.Adhes" user "B.Adhesive")
		(13 "F.Paste" user "Package Geometry/Pastemask Top")
		(15 "B.Paste" user "Package Geometry/Pastemask Bottom")
		(5 "F.SilkS" user "Ref Des/Silkscreen Top")
		(7 "B.SilkS" user "Ref Des/Silkscreen Bottom")
		(1 "F.Mask" user "Board Geometry/Soldermask Top")
		(3 "B.Mask" user "Board Geometry/Soldermask Bottom")
		(17 "Dwgs.User" user "User.Drawings")
		(19 "Cmts.User" user "User.Comments")
		(21 "Eco1.User" user "User.Eco1")
		(23 "Eco2.User" user "User.Eco2")
		(25 "Edge.Cuts" user "Board Geometry/Outline")
		(27 "Margin" user)
		(31 "F.CrtYd" user "Package Geometry/Place Bound Top")
		(29 "B.CrtYd" user "Package Geometry/Place Bound Bottom")
		(35 "F.Fab" user "Ref Des/Assembly Top")
		(33 "B.Fab" user "Ref Des/Assembly Bottom")
	)
	(footprint ""
		(layer "B.Cu")
		(at 390.020048 -314.180474 -90)
		(property "Reference" "R573"
			(at 0 0 90)
			(layer "B.SilkS")
			(hide yes)
			(effects
				(font
					(size 1.27 1.27)
				)
				(justify mirror)
			)
		)
		(property "Value" ""
			(at 0 0 90)
			(layer "B.Fab")
			(effects
				(font
					(size 1.27 1.27)
				)
				(justify mirror)
			)
		)
		(duplicate_pad_numbers_are_jumpers no)
		(fp_line
			(start -0.7874 0.4064)
			(end 0.7874 0.4064)
			(stroke
				(width 0.1524)
				(type default)
			)
			(layer "B.SilkS")
		)
		(fp_line
			(start 0.7874 0.4064)
			(end 0.7874 -0.4064)
			(stroke
				(width 0.1524)
				(type default)
			)
			(layer "B.SilkS")
		)
		(fp_line
			(start -0.7874 -0.4064)
			(end -0.7874 0.4064)
			(stroke
				(width 0.1524)
				(type default)
			)
			(layer "B.SilkS")
		)
		(fp_line
			(start 0.7874 -0.4064)
			(end -0.7874 -0.4064)
			(stroke
				(width 0.1524)
				(type default)
			)
			(layer "B.SilkS")
		)
		(fp_line
			(start -0.67945 0.3048)
			(end -0.120396 0.3048)
			(stroke
				(width 0.1)
				(type default)
			)
			(layer "B.Fab")
		)
		(fp_line
			(start -0.120396 0.3048)
			(end -0.120396 0.2794)
			(stroke
				(width 0.1)
				(type default)
			)
			(layer "B.Fab")
		)
		(fp_line
			(start 0.12065 0.3048)
			(end 0.67945 0.3048)
			(stroke
				(width 0.1)
				(type default)
			)
			(layer "B.Fab")
		)
		(fp_line
			(start 0.67945 0.3048)
			(end 0.67945 -0.305054)
			(stroke
				(width 0.1)
				(type default)
			)
			(layer "B.Fab")
		)
		(fp_line
			(start -0.120396 0.2794)
			(end 0.12065 0.2794)
			(stroke
				(width 0.1)
				(type default)
			)
			(layer "B.Fab")
		)
		(fp_line
			(start 0.12065 0.2794)
			(end 0.12065 0.3048)
			(stroke
				(width 0.1)
				(type default)
			)
			(layer "B.Fab")
		)
		(fp_line
			(start -0.12065 -0.2794)
			(end -0.12065 -0.3048)
			(stroke
				(width 0.1)
				(type default)
			)
			(layer "B.Fab")
		)
		(fp_line
			(start 0.12065 -0.2794)
			(end -0.12065 -0.2794)
			(stroke
				(width 0.1)
				(type default)
			)
			(layer "B.Fab")
		)
		(fp_line
			(start -0.67945 -0.3048)
			(end -0.67945 0.3048)
			(stroke
				(width 0.1)
				(type default)
			)
			(layer "B.Fab")
		)
		(fp_line
			(start -0.12065 -0.3048)
			(end -0.67945 -0.3048)
			(stroke
				(width 0.1)
				(type default)
			)
			(layer "B.Fab")
		)
		(fp_line
			(start 0.12065 -0.305054)
			(end 0.12065 -0.2794)
			(stroke
				(width 0.1)
				(type default)
			)
			(layer "B.Fab")
		)
		(fp_line
			(start 0.67945 -0.305054)
			(end 0.12065 -0.305054)
			(stroke
				(width 0.1)
				(type default)
			)
			(layer "B.Fab")
		)
		(pad "1" smd circle
			(at 0.40005 0 90)
			(size 0 0)
			(layers "B.Cu" "B.Mask" "B.Paste")
			(net "CLK_CPU0_RTCCLK")
		)
		(pad "2" smd circle
			(at -0.40005 0 90)
			(size 0 0)
			(layers "B.Cu" "B.Mask" "B.Paste")
			(net "XTAL_CPU1_X32K_X1")
		)
	)
	(footprint ""
		(layer "B.Cu")
		(at 372.937278 -141.472158 180)
		(property "Reference" "R315"
			(at 0 0 0)
			(layer "B.SilkS")
			(hide yes)
			(effects
				(font
					(size 1.27 1.27)
				)
				(justify mirror)
			)
		)
		(property "Value" ""
			(at 0 0 0)
			(layer "B.Fab")
			(effects
				(font
					(size 1.27 1.27)
				)
				(justify mirror)
			)
		)
		(duplicate_pad_numbers_are_jumpers no)
		(fp_line
			(start 0.7874 0.4064)
			(end 0.7874 -0.4064)
			(stroke
				(width 0.1524)
				(type default)
			)
			(layer "B.SilkS")
		)
		(fp_line
			(start 0.7874 -0.4064)
			(end -0.7874 -0.4064)
			(stroke
				(width 0.1524)
				(type default)
			)
			(layer "B.SilkS")
		)
		(fp_line
			(start -0.7874 0.4064)
			(end 0.7874 0.4064)
			(stroke
				(width 0.1524)
				(type default)
			)
			(layer "B.SilkS")
		)
		(fp_line
			(start -0.7874 -0.4064)
			(end -0.7874 0.4064)
			(stroke
				(width 0.1524)
				(type default)
			)
			(layer "B.SilkS")
		)
		(fp_line
			(start 0.67945 0.3048)
			(end 0.67945 -0.305054)
			(stroke
				(width 0.1)
				(type default)
			)
			(layer "B.Fab")
		)
		(fp_line
			(start 0.67945 -0.305054)
			(end 0.12065 -0.305054)
			(stroke
				(width 0.1)
				(type default)
			)
			(layer "B.Fab")
		)
		(fp_line
			(start 0.12065 0.3048)
			(end 0.67945 0.3048)
			(stroke
				(width 0.1)
				(type default)
			)
			(layer "B.Fab")
		)
		(fp_line
			(start 0.12065 0.2794)
			(end 0.12065 0.3048)
			(stroke
				(width 0.1)
				(type default)
			)
			(layer "B.Fab")
		)
		(fp_line
			(start 0.12065 -0.2794)
			(end -0.12065 -0.2794)
			(stroke
				(width 0.1)
				(type default)
			)
			(layer "B.Fab")
		)
		(fp_line
			(start 0.12065 -0.305054)
			(end 0.12065 -0.2794)
			(stroke
				(width 0.1)
				(type default)
			)
			(layer "B.Fab")
		)
		(fp_line
			(start -0.120396 0.3048)
			(end -0.120396 0.2794)
			(stroke
				(width 0.1)
				(type default)
			)
			(layer "B.Fab")
		)
		(fp_line
			(start -0.120396 0.2794)
			(end 0.12065 0.2794)
			(stroke
				(width 0.1)
				(type default)
			)
			(layer "B.Fab")
		)
		(fp_line
			(start -0.12065 -0.2794)
			(end -0.12065 -0.3048)
			(stroke
				(width 0.1)
				(type default)
			)
			(layer "B.Fab")
		)
		(fp_line
			(start -0.12065 -0.3048)
			(end -0.67945 -0.3048)
			(stroke
				(width 0.1)
				(type default)
			)
			(layer "B.Fab")
		)
		(fp_line
			(start -0.67945 0.3048)
			(end -0.120396 0.3048)
			(stroke
				(width 0.1)
				(type default)
			)
			(layer "B.Fab")
		)
		(fp_line
			(start -0.67945 -0.3048)
			(end -0.67945 0.3048)
			(stroke
				(width 0.1)
				(type default)
			)
			(layer "B.Fab")
		)
		(pad "1" smd circle
			(at 0.40005 0)
			(size 0 0)
			(layers "B.Cu" "B.Mask" "B.Paste")
			(net "PVDDCR_CPU0_P0_RESET_N")
		)
		(pad "2" smd circle
			(at -0.40005 0)
			(size 0 0)
			(layers "B.Cu" "B.Mask" "B.Paste")
			(net "PVDDCR_CPU0_P0_RESET_N_R")
		)
	)
	(footprint ""
		(layer "B.Cu")
		(at 8.19277 -112.04702)
		(property "Reference" "C5232"
			(at 0 0 0)
			(layer "B.SilkS")
			(hide yes)
			(effects
				(font
					(size 1.27 1.27)
				)
				(justify mirror)
			)
		)
		(property "Value" ""
			(at 0 0 0)
			(layer "B.Fab")
			(effects
				(font
					(size 1.27 1.27)
				)
				(justify mirror)
			)
		)
		(duplicate_pad_numbers_are_jumpers no)
		(fp_line
			(start -0.7874 -0.4064)
			(end -0.7874 0.4064)
			(stroke
				(width 0.1524)
				(type default)
			)
			(layer "B.SilkS")
		)
		(fp_line
			(start -0.7874 0.4064)
			(end 0.7874 0.4064)
			(stroke
				(width 0.1524)
				(type default)
			)
			(layer "B.SilkS")
		)
		(fp_line
			(start 0.7874 -0.4064)
			(end -0.7874 -0.4064)
			(stroke
				(width 0.1524)
				(type default)
			)
			(layer "B.SilkS")
		)
		(fp_line
			(start 0.7874 0.4064)
			(end 0.7874 -0.4064)
			(stroke
				(width 0.1524)
				(type default)
			)
			(layer "B.SilkS")
		)
		(fp_line
			(start -0.67945 -0.3048)
			(end -0.67945 0.3048)
			(stroke
				(width 0.1)
				(type default)
			)
			(layer "B.Fab")
		)
		(fp_line
			(start -0.67945 0.3048)
			(end -0.120396 0.3048)
			(stroke
				(width 0.1)
				(type default)
			)
			(layer "B.Fab")
		)
		(fp_line
			(start -0.12065 -0.3048)
			(end -0.67945 -0.3048)
			(stroke
				(width 0.1)
				(type default)
			)
			(layer "B.Fab")
		)
		(fp_line
			(start -0.12065 -0.2794)
			(end -0.12065 -0.3048)
			(stroke
				(width 0.1)
				(type default)
			)
			(layer "B.Fab")
		)
		(fp_line
			(start -0.120396 0.2794)
			(end 0.12065 0.2794)
			(stroke
				(width 0.1)
				(type default)
			)
			(layer "B.Fab")
		)
		(fp_line
			(start -0.120396 0.3048)
			(end -0.120396 0.2794)
			(stroke
				(width 0.1)
				(type default)
			)
			(layer "B.Fab")
		)
		(fp_line
			(start 0.12065 -0.305054)
			(end 0.12065 -0.2794)
			(stroke
				(width 0.1)
				(type default)
			)
			(layer "B.Fab")
		)
		(fp_line
			(start 0.12065 -0.2794)
			(end -0.12065 -0.2794)
			(stroke
				(width 0.1)
				(type default)
			)
			(layer "B.Fab")
		)
		(fp_line
			(start 0.12065 0.2794)
			(end 0.12065 0.3048)
			(stroke
				(width 0.1)
				(type default)
			)
			(layer "B.Fab")
		)
		(fp_line
			(start 0.12065 0.3048)
			(end 0.67945 0.3048)
			(stroke
				(width 0.1)
				(type default)
			)
			(layer "B.Fab")
		)
		(fp_line
			(start 0.67945 -0.305054)
			(end 0.12065 -0.305054)
			(stroke
				(width 0.1)
				(type default)
			)
			(layer "B.Fab")
		)
		(fp_line
			(start 0.67945 0.3048)
			(end 0.67945 -0.305054)
			(stroke
				(width 0.1)
				(type default)
			)
			(layer "B.Fab")
		)
		(pad "1" smd circle
			(at 0.40005 0 180)
			(size 0 0)
			(layers "B.Cu" "B.Mask" "B.Paste")
			(net "PD_U5201_RSTN")
		)
		(pad "2" smd circle
			(at -0.40005 0 180)
			(size 0 0)
			(layers "B.Cu" "B.Mask" "B.Paste")
			(net "GND")
		)
	)
	(footprint ""
		(layer "B.Cu")
		(at 390.779762 -416.899344 90)
		(property "Reference" "C6610"
			(at 0 0 90)
			(layer "B.SilkS")
			(hide yes)
			(effects
				(font
					(size 1.27 1.27)
				)
				(justify mirror)
			)
		)
		(property "Value" ""
			(at 0 0 90)
			(layer "B.Fab")
			(effects
				(font
					(size 1.27 1.27)
				)
				(justify mirror)
			)
		)
		(duplicate_pad_numbers_are_jumpers no)
		(fp_line
			(start 0.299974 -0.150114)
			(end -0.299974 -0.150114)
			(stroke
				(width 0.1)
				(type default)
			)
			(layer "B.Fab")
		)
		(fp_line
			(start -0.299974 -0.150114)
			(end -0.299974 0.150114)
			(stroke
				(width 0.1)
				(type default)
			)
			(layer "B.Fab")
		)
		(fp_line
			(start 0.299974 0.150114)
			(end 0.299974 -0.150114)
			(stroke
				(width 0.1)
				(type default)
			)
			(layer "B.Fab")
		)
		(fp_line
			(start -0.299974 0.150114)
			(end 0.299974 0.150114)
			(stroke
				(width 0.1)
				(type default)
			)
			(layer "B.Fab")
		)
		(pad "1" smd rect
			(at 0.2667 0 270)
			(size 0.3048 0.381)
			(layers "B.Cu" "B.Mask" "B.Paste")
			(net "P5E_CPU0_P3_TX_BUF_C_DN<6>")
		)
		(pad "2" smd rect
			(at -0.2667 0 270)
			(size 0.3048 0.381)
			(layers "B.Cu" "B.Mask" "B.Paste")
			(net "P5E_CPU0_P3_TX_BUF_DN<6>")
		)
	)
	(footprint ""
		(layer "B.Cu")
		(at 110.149386 -266.005564)
		(property "Reference" "C2285"
			(at 0 0 0)
			(layer "B.SilkS")
			(hide yes)
			(effects
				(font
					(size 1.27 1.27)
				)
				(justify mirror)
			)
		)
		(property "Value" ""
			(at 0 0 0)
			(layer "B.Fab")
			(effects
				(font
					(size 1.27 1.27)
				)
				(justify mirror)
			)
		)
		(duplicate_pad_numbers_are_jumpers no)
		(fp_line
			(start -0.7874 -0.4064)
			(end -0.7874 0.4064)
			(stroke
				(width 0.1524)
				(type default)
			)
			(layer "B.SilkS")
		)
		(fp_line
			(start -0.7874 0.4064)
			(end 0.7874 0.4064)
			(stroke
				(width 0.1524)
				(type default)
			)
			(layer "B.SilkS")
		)
		(fp_line
			(start 0.7874 -0.4064)
			(end -0.7874 -0.4064)
			(stroke
				(width 0.1524)
				(type default)
			)
			(layer "B.SilkS")
		)
		(fp_line
			(start 0.7874 0.4064)
			(end 0.7874 -0.4064)
			(stroke
				(width 0.1524)
				(type default)
			)
			(layer "B.SilkS")
		)
		(fp_line
			(start -0.67945 -0.3048)
			(end -0.67945 0.3048)
			(stroke
				(width 0.1)
				(type default)
			)
			(layer "B.Fab")
		)
		(fp_line
			(start -0.67945 0.3048)
			(end -0.120396 0.3048)
			(stroke
				(width 0.1)
				(type default)
			)
			(layer "B.Fab")
		)
		(fp_line
			(start -0.12065 -0.3048)
			(end -0.67945 -0.3048)
			(stroke
				(width 0.1)
				(type default)
			)
			(layer "B.Fab")
		)
		(fp_line
			(start -0.12065 -0.2794)
			(end -0.12065 -0.3048)
			(stroke
				(width 0.1)
				(type default)
			)
			(layer "B.Fab")
		)
		(fp_line
			(start -0.120396 0.2794)
			(end 0.12065 0.2794)
			(stroke
				(width 0.1)
				(type default)
			)
			(layer "B.Fab")
		)
		(fp_line
			(start -0.120396 0.3048)
			(end -0.120396 0.2794)
			(stroke
				(width 0.1)
				(type default)
			)
			(layer "B.Fab")
		)
		(fp_line
			(start 0.12065 -0.305054)
			(end 0.12065 -0.2794)
			(stroke
				(width 0.1)
				(type default)
			)
			(layer "B.Fab")
		)
		(fp_line
			(start 0.12065 -0.2794)
			(end -0.12065 -0.2794)
			(stroke
				(width 0.1)
				(type default)
			)
			(layer "B.Fab")
		)
		(fp_line
			(start 0.12065 0.2794)
			(end 0.12065 0.3048)
			(stroke
				(width 0.1)
				(type default)
			)
			(layer "B.Fab")
		)
		(fp_line
			(start 0.12065 0.3048)
			(end 0.67945 0.3048)
			(stroke
				(width 0.1)
				(type default)
			)
			(layer "B.Fab")
		)
		(fp_line
			(start 0.67945 -0.305054)
			(end 0.12065 -0.305054)
			(stroke
				(width 0.1)
				(type default)
			)
			(layer "B.Fab")
		)
		(fp_line
			(start 0.67945 0.3048)
			(end 0.67945 -0.305054)
			(stroke
				(width 0.1)
				(type default)
			)
			(layer "B.Fab")
		)
		(pad "1" smd circle
			(at 0.40005 0 180)
			(size 0 0)
			(layers "B.Cu" "B.Mask" "B.Paste")
			(net "PVDD11_S3_P1")
		)
		(pad "2" smd circle
			(at -0.40005 0 180)
			(size 0 0)
			(layers "B.Cu" "B.Mask" "B.Paste")
			(net "GND")
		)
	)
	(footprint ""
		(layer "B.Cu")
		(at 109.766862 -177.112676 90)
		(property "Reference" "PR194"
			(at 0 0 90)
			(layer "B.SilkS")
			(hide yes)
			(effects
				(font
					(size 1.27 1.27)
				)
				(justify mirror)
			)
		)
		(property "Value" ""
			(at 0 0 90)
			(layer "B.Fab")
			(effects
				(font
					(size 1.27 1.27)
				)
				(justify mirror)
			)
		)
		(duplicate_pad_numbers_are_jumpers no)
		(fp_line
			(start 0.7874 -0.4064)
			(end -0.7874 -0.4064)
			(stroke
				(width 0.1524)
				(type default)
			)
			(layer "B.SilkS")
		)
		(fp_line
			(start -0.7874 -0.4064)
			(end -0.7874 0.4064)
			(stroke
				(width 0.1524)
				(type default)
			)
			(layer "B.SilkS")
		)
		(fp_line
			(start 0.7874 0.4064)
			(end 0.7874 -0.4064)
			(stroke
				(width 0.1524)
				(type default)
			)
			(layer "B.SilkS")
		)
		(fp_line
			(start -0.7874 0.4064)
			(end 0.7874 0.4064)
			(stroke
				(width 0.1524)
				(type default)
			)
			(layer "B.SilkS")
		)
		(fp_line
			(start 0.67945 -0.305054)
			(end 0.12065 -0.305054)
			(stroke
				(width 0.1)
				(type default)
			)
			(layer "B.Fab")
		)
		(fp_line
			(start 0.12065 -0.305054)
			(end 0.12065 -0.2794)
			(stroke
				(width 0.1)
				(type default)
			)
			(layer "B.Fab")
		)
		(fp_line
			(start -0.12065 -0.3048)
			(end -0.67945 -0.3048)
			(stroke
				(width 0.1)
				(type default)
			)
			(layer "B.Fab")
		)
		(fp_line
			(start -0.67945 -0.3048)
			(end -0.67945 0.3048)
			(stroke
				(width 0.1)
				(type default)
			)
			(layer "B.Fab")
		)
		(fp_line
			(start 0.12065 -0.2794)
			(end -0.12065 -0.2794)
			(stroke
				(width 0.1)
				(type default)
			)
			(layer "B.Fab")
		)
		(fp_line
			(start -0.12065 -0.2794)
			(end -0.12065 -0.3048)
			(stroke
				(width 0.1)
				(type default)
			)
			(layer "B.Fab")
		)
		(fp_line
			(start 0.12065 0.2794)
			(end 0.12065 0.3048)
			(stroke
				(width 0.1)
				(type default)
			)
			(layer "B.Fab")
		)
		(fp_line
			(start -0.120396 0.2794)
			(end 0.12065 0.2794)
			(stroke
				(width 0.1)
				(type default)
			)
			(layer "B.Fab")
		)
		(fp_line
			(start 0.67945 0.3048)
			(end 0.67945 -0.305054)
			(stroke
				(width 0.1)
				(type default)
			)
			(layer "B.Fab")
		)
		(fp_line
			(start 0.12065 0.3048)
			(end 0.67945 0.3048)
			(stroke
				(width 0.1)
				(type default)
			)
			(layer "B.Fab")
		)
		(fp_line
			(start -0.120396 0.3048)
			(end -0.120396 0.2794)
			(stroke
				(width 0.1)
				(type default)
			)
			(layer "B.Fab")
		)
		(fp_line
			(start -0.67945 0.3048)
			(end -0.120396 0.3048)
			(stroke
				(width 0.1)
				(type default)
			)
			(layer "B.Fab")
		)
		(pad "1" smd circle
			(at 0.40005 0 270)
			(size 0 0)
			(layers "B.Cu" "B.Mask" "B.Paste")
			(net "PVDDCR_CPU0_P1_PVCC")
		)
		(pad "2" smd circle
			(at -0.40005 0 270)
			(size 0 0)
			(layers "B.Cu" "B.Mask" "B.Paste")
			(net "PVDDCR_CPU0_P1_VCC4")
		)
	)
	(footprint ""
		(layer "B.Cu")
		(at 406.698958 -325.878952 180)
		(property "Reference" "R434"
			(at 0 0 0)
			(layer "B.SilkS")
			(hide yes)
			(effects
				(font
					(size 1.27 1.27)
				)
				(justify mirror)
			)
		)
		(property "Value" ""
			(at 0 0 0)
			(layer "B.Fab")
			(effects
				(font
					(size 1.27 1.27)
				)
				(justify mirror)
			)
		)
		(duplicate_pad_numbers_are_jumpers no)
		(fp_line
			(start 0.7874 0.4064)
			(end 0.7874 -0.4064)
			(stroke
				(width 0.1524)
				(type default)
			)
			(layer "B.SilkS")
		)
		(fp_line
			(start 0.7874 -0.4064)
			(end -0.7874 -0.4064)
			(stroke
				(width 0.1524)
				(type default)
			)
			(layer "B.SilkS")
		)
		(fp_line
			(start -0.7874 0.4064)
			(end 0.7874 0.4064)
			(stroke
				(width 0.1524)
				(type default)
			)
			(layer "B.SilkS")
		)
		(fp_line
			(start -0.7874 -0.4064)
			(end -0.7874 0.4064)
			(stroke
				(width 0.1524)
				(type default)
			)
			(layer "B.SilkS")
		)
		(fp_line
			(start 0.67945 0.3048)
			(end 0.67945 -0.305054)
			(stroke
				(width 0.1)
				(type default)
			)
			(layer "B.Fab")
		)
		(fp_line
			(start 0.67945 -0.305054)
			(end 0.12065 -0.305054)
			(stroke
				(width 0.1)
				(type default)
			)
			(layer "B.Fab")
		)
		(fp_line
			(start 0.12065 0.3048)
			(end 0.67945 0.3048)
			(stroke
				(width 0.1)
				(type default)
			)
			(layer "B.Fab")
		)
		(fp_line
			(start 0.12065 0.2794)
			(end 0.12065 0.3048)
			(stroke
				(width 0.1)
				(type default)
			)
			(layer "B.Fab")
		)
		(fp_line
			(start 0.12065 -0.2794)
			(end -0.12065 -0.2794)
			(stroke
				(width 0.1)
				(type default)
			)
			(layer "B.Fab")
		)
		(fp_line
			(start 0.12065 -0.305054)
			(end 0.12065 -0.2794)
			(stroke
				(width 0.1)
				(type default)
			)
			(layer "B.Fab")
		)
		(fp_line
			(start -0.120396 0.3048)
			(end -0.120396 0.2794)
			(stroke
				(width 0.1)
				(type default)
			)
			(layer "B.Fab")
		)
		(fp_line
			(start -0.120396 0.2794)
			(end 0.12065 0.2794)
			(stroke
				(width 0.1)
				(type default)
			)
			(layer "B.Fab")
		)
		(fp_line
			(start -0.12065 -0.2794)
			(end -0.12065 -0.3048)
			(stroke
				(width 0.1)
				(type default)
			)
			(layer "B.Fab")
		)
		(fp_line
			(start -0.12065 -0.3048)
			(end -0.67945 -0.3048)
			(stroke
				(width 0.1)
				(type default)
			)
			(layer "B.Fab")
		)
		(fp_line
			(start -0.67945 0.3048)
			(end -0.120396 0.3048)
			(stroke
				(width 0.1)
				(type default)
			)
			(layer "B.Fab")
		)
		(fp_line
			(start -0.67945 -0.3048)
			(end -0.67945 0.3048)
			(stroke
				(width 0.1)
				(type default)
			)
			(layer "B.Fab")
		)
		(pad "1" smd circle
			(at 0.40005 0)
			(size 0 0)
			(layers "B.Cu" "B.Mask" "B.Paste")
			(net "CPU0_PWR_GD_OUT")
		)
		(pad "2" smd circle
			(at -0.40005 0)
			(size 0 0)
			(layers "B.Cu" "B.Mask" "B.Paste")
			(net "CPU1_PWR_GD_IN")
		)
	)
)
